(kicad_pcb
	(version 20260206)
	(generator "pcbnew")
	(generator_version "10.0")
	(general
		(thickness 1.6)
		(legacy_teardrops no)
	)
	(paper "A4")
	(title_block
		(title "04192023_DAF0TMB3IC0_F0TG_MB_C_brd_V02_OCP.brd")
		(comment 1 "Grand Teton / footprints 2909-2914 of 8354")
	)
	(layers
		(0 "F.Cu" signal "TOP")
		(4 "In1.Cu" signal "GND")
		(6 "In2.Cu" signal "IN1")
		(8 "In3.Cu" signal "GND1")
		(10 "In4.Cu" signal "IN2")
		(12 "In5.Cu" signal "GND2")
		(14 "In6.Cu" signal "IN3")
		(16 "In7.Cu" signal "GND3")
		(18 "In8.Cu" signal "VCC")
		(20 "In9.Cu" signal "VCC1")
		(22 "In10.Cu" signal "GND4")
		(24 "In11.Cu" signal "IN4")
		(26 "In12.Cu" signal "GND5")
		(28 "In13.Cu" signal "IN5")
		(30 "In14.Cu" signal "GND6")
		(32 "In15.Cu" signal "IN6")
		(34 "In16.Cu" signal "GND7")
		(2 "B.Cu" signal "BOTTOM")
		(9 "F.Adhes" user "F.Adhesive")
		(11 "B.Adhes" user "B.Adhesive")
		(13 "F.Paste" user "Package Geometry/Pastemask Top")
		(15 "B.Paste" user "Package Geometry/Pastemask Bottom")
		(5 "F.SilkS" user "Ref Des/Silkscreen Top")
		(7 "B.SilkS" user "Ref Des/Silkscreen Bottom")
		(1 "F.Mask" user "Board Geometry/Soldermask Top")
		(3 "B.Mask" user "Board Geometry/Soldermask Bottom")
		(17 "Dwgs.User" user "User.Drawings")
		(19 "Cmts.User" user "User.Comments")
		(21 "Eco1.User" user "User.Eco1")
		(23 "Eco2.User" user "User.Eco2")
		(25 "Edge.Cuts" user "Board Geometry/Outline")
		(27 "Margin" user)
		(31 "F.CrtYd" user "Package Geometry/Place Bound Top")
		(29 "B.CrtYd" user "Package Geometry/Place Bound Bottom")
		(35 "F.Fab" user "Ref Des/Assembly Top")
		(33 "B.Fab" user "Ref Des/Assembly Bottom")
	)
	(footprint ""
		(layer "F.Cu")
		(at 16.623284 -423.13352 -90)
		(property "Reference" "U6000"
			(at -5.784342 3.991102 0)
			(unlocked yes)
			(layer "F.SilkS")
			(effects
				(font
					(size 0.7874 0.5842)
					(thickness 0.1524)
				)
				(justify left)
			)
		)
		(property "Value" ""
			(at 0 0 270)
			(layer "F.Fab")
			(effects
				(font
					(size 1.27 1.27)
				)
			)
		)
		(duplicate_pad_numbers_are_jumpers no)
		(fp_line
			(start -2.050034 2.050034)
			(end -2.050034 1.524)
			(stroke
				(width 0.1524)
				(type default)
			)
			(layer "F.SilkS")
		)
		(fp_line
			(start -1.524 2.050034)
			(end -2.050034 2.050034)
			(stroke
				(width 0.1524)
				(type default)
			)
			(layer "F.SilkS")
		)
		(fp_line
			(start 2.050034 2.050034)
			(end 1.524 2.050034)
			(stroke
				(width 0.1524)
				(type default)
			)
			(layer "F.SilkS")
		)
		(fp_line
			(start 2.050034 1.524)
			(end 2.050034 2.050034)
			(stroke
				(width 0.1524)
				(type default)
			)
			(layer "F.SilkS")
		)
		(fp_line
			(start -2.050034 -1.524)
			(end -2.050034 -2.050034)
			(stroke
				(width 0.1524)
				(type default)
			)
			(layer "F.SilkS")
		)
		(fp_line
			(start -2.050034 -2.050034)
			(end -1.524 -2.050034)
			(stroke
				(width 0.1524)
				(type default)
			)
			(layer "F.SilkS")
		)
		(fp_line
			(start 1.524 -2.050034)
			(end 2.050034 -2.050034)
			(stroke
				(width 0.1524)
				(type default)
			)
			(layer "F.SilkS")
		)
		(fp_line
			(start 2.050034 -2.050034)
			(end 2.050034 -1.524)
			(stroke
				(width 0.1524)
				(type default)
			)
			(layer "F.SilkS")
		)
		(fp_rect
			(start -2.050034 -2.126234)
			(end -2.634234 -1.542034)
			(stroke
				(width 0)
				(type default)
			)
			(fill yes)
			(layer "F.SilkS")
		)
		(fp_line
			(start -2.050034 2.050034)
			(end -2.050034 -2.050034)
			(stroke
				(width 0.1)
				(type default)
			)
			(layer "F.Fab")
		)
		(fp_line
			(start 2.050034 2.050034)
			(end -2.050034 2.050034)
			(stroke
				(width 0.1)
				(type default)
			)
			(layer "F.Fab")
		)
		(fp_line
			(start -2.050034 -2.050034)
			(end 2.050034 -2.050034)
			(stroke
				(width 0.1)
				(type default)
			)
			(layer "F.Fab")
		)
		(fp_line
			(start 2.050034 -2.050034)
			(end 2.050034 2.050034)
			(stroke
				(width 0.1)
				(type default)
			)
			(layer "F.Fab")
		)
		(fp_poly
			(pts
				(xy -2.634234 -1.542034) (xy -2.050034 -1.542034) (xy -2.050034 -2.126234) (xy -2.634234 -2.126234)
			)
			(stroke
				(width 0)
				(type default)
			)
			(fill yes)
			(layer "F.Fab")
		)
		(pad "1" smd circle
			(at -1.89992 -1.249934 180)
			(size 0 0)
			(layers "F.Cu" "F.Mask" "F.Paste")
			(net "FM_P2E_BUF2_EQB0")
		)
		(pad "2" smd circle
			(at -1.89992 -0.750062 180)
			(size 0 0)
			(layers "F.Cu" "F.Mask" "F.Paste")
			(net "FM_P2E_BUF2_EQB1")
		)
		(pad "3" smd circle
			(at -1.89992 -0.249936 180)
			(size 0 0)
			(layers "F.Cu" "F.Mask" "F.Paste")
			(net "PD_P2E_BUF2_ENSMB")
		)
		(pad "4" smd circle
			(at -1.89992 0.249936 180)
			(size 0 0)
			(layers "F.Cu" "F.Mask" "F.Paste")
			(net "FM_P2E_BUF2_VODA_DB")
		)
		(pad "5" smd circle
			(at -1.89992 0.750062 180)
			(size 0 0)
			(layers "F.Cu" "F.Mask" "F.Paste")
			(net "FM_P2E_BUF2_VODB_DB")
		)
		(pad "6" smd circle
			(at -1.89992 1.249934 180)
			(size 0 0)
			(layers "F.Cu" "F.Mask" "F.Paste")
			(net "FM_P2E_EN2_N")
		)
		(pad "7" smd circle
			(at -1.249934 1.89992 270)
			(size 0 0)
			(layers "F.Cu" "F.Mask" "F.Paste")
			(net "P2E_MB_BMC_TX_BUF2_DP<0>")
		)
		(pad "8" smd circle
			(at -0.750062 1.89992 270)
			(size 0 0)
			(layers "F.Cu" "F.Mask" "F.Paste")
			(net "P2E_MB_BMC_TX_BUF2_DN<0>")
		)
		(pad "9" smd circle
			(at -0.249936 1.89992 270)
			(size 0 0)
			(layers "F.Cu" "F.Mask" "F.Paste")
			(net "FM_P2E_BUF2_EQA1")
		)
		(pad "10" smd circle
			(at 0.249936 1.89992 270)
			(size 0 0)
			(layers "F.Cu" "F.Mask" "F.Paste")
			(net "FM_P2E_BUF2_EQA0")
		)
		(pad "11" smd circle
			(at 0.750062 1.89992 270)
			(size 0 0)
			(layers "F.Cu" "F.Mask" "F.Paste")
			(net "P2E_MB_BMC_RX_R2_DP<0>")
		)
		(pad "12" smd circle
			(at 1.249934 1.89992 270)
			(size 0 0)
			(layers "F.Cu" "F.Mask" "F.Paste")
			(net "P2E_MB_BMC_RX_R2_DN<0>")
		)
		(pad "13" smd circle
			(at 1.89992 1.249934 180)
			(size 0 0)
			(layers "F.Cu" "F.Mask" "F.Paste")
			(net "NC_RES")
		)
		(pad "14" smd circle
			(at 1.89992 0.750062 180)
			(size 0 0)
			(layers "F.Cu" "F.Mask" "F.Paste")
			(net "FM_P2E_BUF2_SD_TH")
		)
		(pad "15" smd circle
			(at 1.89992 0.249936 180)
			(size 0 0)
			(layers "F.Cu" "F.Mask" "F.Paste")
			(net "P3V3_AUX")
		)
		(pad "16" smd circle
			(at 1.89992 -0.249936 180)
			(size 0 0)
			(layers "F.Cu" "F.Mask" "F.Paste")
			(net "GND")
		)
		(pad "17" smd circle
			(at 1.89992 -0.750062 180)
			(size 0 0)
			(layers "F.Cu" "F.Mask" "F.Paste")
			(net "FM_P2E_BUF2_VOD_SEL")
		)
		(pad "18" smd circle
			(at 1.89992 -1.249934 180)
			(size 0 0)
			(layers "F.Cu" "F.Mask" "F.Paste")
			(net "FM_P2E_BUF2_RXDET")
		)
		(pad "19" smd circle
			(at 1.249934 -1.89992 270)
			(size 0 0)
			(layers "F.Cu" "F.Mask" "F.Paste")
			(net "P2E_MB_BMC_RX_BUF2_C_DN<0>")
		)
		(pad "20" smd circle
			(at 0.750062 -1.89992 270)
			(size 0 0)
			(layers "F.Cu" "F.Mask" "F.Paste")
			(net "P2E_MB_BMC_RX_BUF2_C_DP<0>")
		)
		(pad "21" smd circle
			(at 0.249936 -1.89992 270)
			(size 0 0)
			(layers "F.Cu" "F.Mask" "F.Paste")
			(net "BUF2_VDD")
		)
		(pad "22" smd circle
			(at -0.249936 -1.89992 270)
			(size 0 0)
			(layers "F.Cu" "F.Mask" "F.Paste")
			(net "BUF2_VDD")
		)
		(pad "23" smd circle
			(at -0.750062 -1.89992 270)
			(size 0 0)
			(layers "F.Cu" "F.Mask" "F.Paste")
			(net "P2E_MB_BMC_TX_C_R2_DN<0>")
		)
		(pad "24" smd circle
			(at -1.249934 -1.89992 270)
			(size 0 0)
			(layers "F.Cu" "F.Mask" "F.Paste")
			(net "P2E_MB_BMC_TX_C_R2_DP<0>")
		)
		(pad "25" smd circle
			(at 0 0 270)
			(size 0 0)
			(layers "F.Cu" "F.Mask" "F.Paste")
			(net "GND")
		)
		(zone
			(layer "F.Cu")
			(hatch none 0.5)
			(connect_pads
				(clearance 0)
			)
			(min_thickness 0.25)
			(keepout
				(tracks not_allowed)
				(vias allowed)
				(pads allowed)
				(copperpour not_allowed)
				(footprints allowed)
			)
			(placement
				(enabled no)
				(sheetname "")
			)
			(fill
				(thermal_gap 0.5)
				(thermal_bridge_width 0.5)
				(island_removal_mode 0)
			)
			(polygon
				(pts
					(xy 16.597884 -424.65752) (xy 16.597884 -424.50512) (xy 15.251684 -424.50512) (xy 15.251684 -421.76192)
					(xy 16.732758 -421.76192) (xy 16.732758 -421.60952) (xy 15.099284 -421.60952) (xy 15.099284 -424.65752)
				)
			)
		)
	)
	(footprint ""
		(layer "F.Cu")
		(at 458.86116 -37.91585)
		(property "Reference" "U8082"
			(at -2.2733 1.990852 0)
			(unlocked yes)
			(layer "F.SilkS")
			(effects
				(font
					(size 0.7874 0.5842)
					(thickness 0.1524)
				)
				(justify left)
			)
		)
		(property "Value" ""
			(at 0 0 0)
			(layer "F.Fab")
			(effects
				(font
					(size 1.27 1.27)
				)
			)
		)
		(duplicate_pad_numbers_are_jumpers no)
		(fp_line
			(start -1.400048 1.100074)
			(end -1.400048 -1.100074)
			(stroke
				(width 0.1524)
				(type default)
			)
			(layer "F.SilkS")
		)
		(fp_line
			(start 1.400048 -1.100074)
			(end -1.400048 -1.100074)
			(stroke
				(width 0.1524)
				(type default)
			)
			(layer "F.SilkS")
		)
		(fp_line
			(start 1.400048 -1.100074)
			(end 1.400048 1.100074)
			(stroke
				(width 0.1524)
				(type default)
			)
			(layer "F.SilkS")
		)
		(fp_line
			(start 1.400048 1.100074)
			(end -1.400048 1.100074)
			(stroke
				(width 0.1524)
				(type default)
			)
			(layer "F.SilkS")
		)
		(fp_poly
			(pts
				(xy -2.055368 -1.405128) (xy -1.705102 -1.755394) (xy -1.529842 -1.229868)
			)
			(stroke
				(width 0)
				(type default)
			)
			(fill yes)
			(layer "F.SilkS")
		)
		(fp_line
			(start -0.674878 -1.100074)
			(end 0.674878 -1.100074)
			(stroke
				(width 0.1)
				(type default)
			)
			(layer "F.Fab")
		)
		(fp_line
			(start -0.674878 1.100074)
			(end -0.674878 -1.100074)
			(stroke
				(width 0.1)
				(type default)
			)
			(layer "F.Fab")
		)
		(fp_line
			(start 0.674878 -1.100074)
			(end 0.674878 1.100074)
			(stroke
				(width 0.1)
				(type default)
			)
			(layer "F.Fab")
		)
		(fp_line
			(start 0.674878 1.100074)
			(end -0.674878 1.100074)
			(stroke
				(width 0.1)
				(type default)
			)
			(layer "F.Fab")
		)
		(fp_poly
			(pts
				(xy -1.590548 -0.649986) (xy -2.606548 -1.157986) (xy -2.606548 -0.141986)
			)
			(stroke
				(width 0)
				(type default)
			)
			(fill yes)
			(layer "F.Fab")
		)
		(pad "1" smd rect
			(at -0.94996 -0.649986 270)
			(size 0.4318 0.6096)
			(layers "F.Cu" "F.Mask" "F.Paste")
			(net "PU_OCP_SFF_WAKE_OE")
		)
		(pad "2" smd rect
			(at -0.94996 0 270)
			(size 0.4318 0.6096)
			(layers "F.Cu" "F.Mask" "F.Paste")
			(net "IRQ_LVC3_OCP_SFF_WAKE_N")
		)
		(pad "3" smd rect
			(at -0.94996 0.649986 270)
			(size 0.4318 0.6096)
			(layers "F.Cu" "F.Mask" "F.Paste")
			(net "GND")
		)
		(pad "4" smd rect
			(at 0.94996 0.649986 270)
			(size 0.4318 0.6096)
			(layers "F.Cu" "F.Mask" "F.Paste")
			(net "OCP_SFF_WAKE_BUFF_N")
		)
		(pad "5" smd rect
			(at 0.94996 -0.649986 270)
			(size 0.4318 0.6096)
			(layers "F.Cu" "F.Mask" "F.Paste")
			(net "P3V3_AUX")
		)
	)
	(footprint ""
		(layer "F.Cu")
		(at 332.252066 -416.899344 -90)
		(property "Reference" "C6519"
			(at 0 0 270)
			(layer "F.SilkS")
			(hide yes)
			(effects
				(font
					(size 1.27 1.27)
				)
			)
		)
		(property "Value" ""
			(at 0 0 270)
			(layer "F.Fab")
			(effects
				(font
					(size 1.27 1.27)
				)
			)
		)
		(duplicate_pad_numbers_are_jumpers no)
		(fp_line
			(start -0.299974 0.150114)
			(end -0.299974 -0.150114)
			(stroke
				(width 0.1)
				(type default)
			)
			(layer "F.Fab")
		)
		(fp_line
			(start 0.299974 0.150114)
			(end -0.299974 0.150114)
			(stroke
				(width 0.1)
				(type default)
			)
			(layer "F.Fab")
		)
		(fp_line
			(start -0.299974 -0.150114)
			(end 0.299974 -0.150114)
			(stroke
				(width 0.1)
				(type default)
			)
			(layer "F.Fab")
		)
		(fp_line
			(start 0.299974 -0.150114)
			(end 0.299974 0.150114)
			(stroke
				(width 0.1)
				(type default)
			)
			(layer "F.Fab")
		)
		(pad "1" smd rect
			(at -0.2667 0 270)
			(size 0.3048 0.381)
			(layers "F.Cu" "F.Mask" "F.Paste")
			(net "P5E_CPU0_P0_TX_BUF_C_DP<9>")
		)
		(pad "2" smd rect
			(at 0.2667 0 270)
			(size 0.3048 0.381)
			(layers "F.Cu" "F.Mask" "F.Paste")
			(net "P5E_CPU0_P0_TX_BUF_DP<9>")
		)
	)
	(footprint ""
		(layer "F.Cu")
		(at 163.039044 -373.03583 -90)
		(property "Reference" "C751"
			(at 0 0 270)
			(layer "F.SilkS")
			(hide yes)
			(effects
				(font
					(size 1.27 1.27)
				)
			)
		)
		(property "Value" ""
			(at 0 0 270)
			(layer "F.Fab")
			(effects
				(font
					(size 1.27 1.27)
				)
			)
		)
		(duplicate_pad_numbers_are_jumpers no)
		(fp_line
			(start -0.299974 0.150114)
			(end -0.299974 -0.150114)
			(stroke
				(width 0.1)
				(type default)
			)
			(layer "F.Fab")
		)
		(fp_line
			(start 0.299974 0.150114)
			(end -0.299974 0.150114)
			(stroke
				(width 0.1)
				(type default)
			)
			(layer "F.Fab")
		)
		(fp_line
			(start -0.299974 -0.150114)
			(end 0.299974 -0.150114)
			(stroke
				(width 0.1)
				(type default)
			)
			(layer "F.Fab")
		)
		(fp_line
			(start 0.299974 -0.150114)
			(end 0.299974 0.150114)
			(stroke
				(width 0.1)
				(type default)
			)
			(layer "F.Fab")
		)
		(pad "1" smd rect
			(at -0.2667 0 270)
			(size 0.3048 0.381)
			(layers "F.Cu" "F.Mask" "F.Paste")
			(net "P5E_CPU1_P2_TX_C_DP<11>")
		)
		(pad "2" smd rect
			(at 0.2667 0 270)
			(size 0.3048 0.381)
			(layers "F.Cu" "F.Mask" "F.Paste")
			(net "P5E_CPU1_P2_TX_DP<11>")
		)
	)
	(footprint ""
		(layer "F.Cu")
		(at 43.543982 -388.030974 90)
		(property "Reference" "R628"
			(at 0 0 90)
			(layer "F.SilkS")
			(hide yes)
			(effects
				(font
					(size 1.27 1.27)
				)
			)
		)
		(property "Value" ""
			(at 0 0 90)
			(layer "F.Fab")
			(effects
				(font
					(size 1.27 1.27)
				)
			)
		)
		(duplicate_pad_numbers_are_jumpers no)
		(fp_line
			(start 0.32512 -0.175006)
			(end 0.32512 0.175006)
			(stroke
				(width 0.1)
				(type default)
			)
			(layer "F.Fab")
		)
		(fp_line
			(start -0.32512 -0.175006)
			(end 0.32512 -0.175006)
			(stroke
				(width 0.1)
				(type default)
			)
			(layer "F.Fab")
		)
		(fp_line
			(start 0.32512 0.175006)
			(end -0.32512 0.175006)
			(stroke
				(width 0.1)
				(type default)
			)
			(layer "F.Fab")
		)
		(fp_line
			(start -0.32512 0.175006)
			(end -0.32512 -0.175006)
			(stroke
				(width 0.1)
				(type default)
			)
			(layer "F.Fab")
		)
		(pad "1" smd rect
			(at -0.2667 0 90)
			(size 0.3048 0.381)
			(layers "F.Cu" "F.Mask" "F.Paste")
			(net "CLK_100M_RETIMER_CPU1_P0_DP")
		)
		(pad "2" smd rect
			(at 0.2667 0 270)
			(size 0.3048 0.381)
			(layers "F.Cu" "F.Mask" "F.Paste")
			(net "GND")
		)
	)
	(footprint ""
		(layer "F.Cu")
		(at 70.7136 -34.788348)
		(property "Reference" "R3569"
			(at 0 0 0)
			(layer "F.SilkS")
			(hide yes)
			(effects
				(font
					(size 1.27 1.27)
				)
			)
		)
		(property "Value" ""
			(at 0 0 0)
			(layer "F.Fab")
			(effects
				(font
					(size 1.27 1.27)
				)
			)
		)
		(duplicate_pad_numbers_are_jumpers no)
		(fp_line
			(start -0.7874 -0.4064)
			(end 0.7874 -0.4064)
			(stroke
				(width 0.1524)
				(type default)
			)
			(layer "F.SilkS")
		)
		(fp_line
			(start -0.7874 0.4064)
			(end -0.7874 -0.4064)
			(stroke
				(width 0.1524)
				(type default)
			)
			(layer "F.SilkS")
		)
		(fp_line
			(start 0.7874 -0.4064)
			(end 0.7874 0.4064)
			(stroke
				(width 0.1524)
				(type default)
			)
			(layer "F.SilkS")
		)
		(fp_line
			(start 0.7874 0.4064)
			(end -0.7874 0.4064)
			(stroke
				(width 0.1524)
				(type default)
			)
			(layer "F.SilkS")
		)
		(fp_line
			(start -0.67945 -0.305054)
			(end -0.12065 -0.305054)
			(stroke
				(width 0.1)
				(type default)
			)
			(layer "F.Fab")
		)
		(fp_line
			(start -0.67945 0.3048)
			(end -0.67945 -0.305054)
			(stroke
				(width 0.1)
				(type default)
			)
			(layer "F.Fab")
		)
		(fp_line
			(start -0.12065 -0.305054)
			(end -0.12065 -0.2794)
			(stroke
				(width 0.1)
				(type default)
			)
			(layer "F.Fab")
		)
		(fp_line
			(start -0.12065 -0.2794)
			(end 0.12065 -0.2794)
			(stroke
				(width 0.1)
				(type default)
			)
			(layer "F.Fab")
		)
		(fp_line
			(start -0.12065 0.2794)
			(end -0.12065 0.3048)
			(stroke
				(width 0.1)
				(type default)
			)
			(layer "F.Fab")
		)
		(fp_line
			(start -0.12065 0.3048)
			(end -0.67945 0.3048)
			(stroke
				(width 0.1)
				(type default)
			)
			(layer "F.Fab")
		)
		(fp_line
			(start 0.120396 0.2794)
			(end -0.12065 0.2794)
			(stroke
				(width 0.1)
				(type default)
			)
			(layer "F.Fab")
		)
		(fp_line
			(start 0.120396 0.3048)
			(end 0.120396 0.2794)
			(stroke
				(width 0.1)
				(type default)
			)
			(layer "F.Fab")
		)
		(fp_line
			(start 0.12065 -0.3048)
			(end 0.67945 -0.3048)
			(stroke
				(width 0.1)
				(type default)
			)
			(layer "F.Fab")
		)
		(fp_line
			(start 0.12065 -0.2794)
			(end 0.12065 -0.3048)
			(stroke
				(width 0.1)
				(type default)
			)
			(layer "F.Fab")
		)
		(fp_line
			(start 0.67945 -0.3048)
			(end 0.67945 0.3048)
			(stroke
				(width 0.1)
				(type default)
			)
			(layer "F.Fab")
		)
		(fp_line
			(start 0.67945 0.3048)
			(end 0.120396 0.3048)
			(stroke
				(width 0.1)
				(type default)
			)
			(layer "F.Fab")
		)
		(pad "1" smd circle
			(at -0.40005 0)
			(size 0 0)
			(layers "F.Cu" "F.Mask" "F.Paste")
			(net "SMB_INA230_3_3V3AUX_SDA_R")
		)
		(pad "2" smd circle
			(at 0.40005 0)
			(size 0 0)
			(layers "F.Cu" "F.Mask" "F.Paste")
			(net "SMB_INA230_3_3V3AUX_SDA_R1")
		)
	)
)
